(kicad_pcb
	(version 20260206)
	(generator "pcbnew")
	(generator_version "10.0")
	(general
		(thickness 1.6)
		(legacy_teardrops no)
	)
	(paper "A4")
	(title_block
		(title "Bryce Canyon_IOM_M2_16342-2_OCP.brd")
		(comment 1 "Bryce Canyon / footprints 753-761 of 1146")
	)
	(layers
		(0 "F.Cu" signal "TOP")
		(4 "In1.Cu" signal "L2GND")
		(6 "In2.Cu" signal "L3")
		(8 "In3.Cu" signal "L4VCC")
		(10 "In4.Cu" signal "L5VCC")
		(12 "In5.Cu" signal "L6")
		(14 "In6.Cu" signal "L7GND")
		(2 "B.Cu" signal "BOTTOM")
		(9 "F.Adhes" user "F.Adhesive")
		(11 "B.Adhes" user "B.Adhesive")
		(13 "F.Paste" user "Package Geometry/Pastemask Top")
		(15 "B.Paste" user "Package Geometry/Pastemask Bottom")
		(5 "F.SilkS" user "Ref Des/Silkscreen Top")
		(7 "B.SilkS" user "Ref Des/Silkscreen Bottom")
		(1 "F.Mask" user "Board Geometry/Soldermask Top")
		(3 "B.Mask" user "Board Geometry/Soldermask Bottom")
		(17 "Dwgs.User" user "User.Drawings")
		(19 "Cmts.User" user "User.Comments")
		(21 "Eco1.User" user "User.Eco1")
		(23 "Eco2.User" user "User.Eco2")
		(25 "Edge.Cuts" user "Board Geometry/Outline")
		(27 "Margin" user)
		(31 "F.CrtYd" user "Package Geometry/Place Bound Top")
		(29 "B.CrtYd" user "Package Geometry/Place Bound Bottom")
		(35 "F.Fab" user "Ref Des/Assembly Top")
		(33 "B.Fab" user "Ref Des/Assembly Bottom")
	)
	(footprint ""
		(layer "B.Cu")
		(at 47.4472 -151.2824)
		(property "Reference" "TP190"
			(at 0 0 0)
			(layer "B.SilkS")
			(hide yes)
			(effects
				(font
					(size 1.27 1.27)
				)
				(justify mirror)
			)
		)
		(property "Value" "TPAD28-2-GP"
			(at 0.0127 -1.6637 0)
			(unlocked yes)
			(layer "B.Fab")
			(hide yes)
			(effects
				(font
					(size 1.016 1.016)
					(thickness 0.1524)
				)
				(justify mirror)
			)
		)
		(property "Device Type" "TPAD28"
			(at 0.0127 -3.1877 0)
			(unlocked yes)
			(layer "B.Fab")
			(hide yes)
			(effects
				(font
					(size 1.016 1.016)
					(thickness 0.1524)
				)
				(justify mirror)
			)
		)
		(duplicate_pad_numbers_are_jumpers no)
		(fp_poly
			(pts
				(arc
					(start 0.3556 0)
					(mid -0.3556 0)
					(end 0.3556 0)
				)
			)
			(stroke
				(width 0)
				(type default)
			)
			(fill no)
			(layer "B.CrtYd")
		)
		(fp_poly
			(pts
				(arc
					(start 0.6096 0)
					(mid -0.6096 0)
					(end 0.6096 0)
				)
			)
			(stroke
				(width 0)
				(type default)
			)
			(fill no)
			(layer "B.Fab")
		)
		(pad "1" smd circle
			(at 0 0 180)
			(size 0.7112 0.7112)
			(layers "B.Cu" "B.Mask" "B.Paste")
			(net "TP_BMC_GPIOL4")
		)
	)
	(footprint ""
		(layer "B.Cu")
		(at 33.9344 -156.464)
		(property "Reference" "R776"
			(at 0 0 0)
			(layer "B.SilkS")
			(hide yes)
			(effects
				(font
					(size 1.27 1.27)
				)
				(justify mirror)
			)
		)
		(property "Value" "1KR2F-3-GP"
			(at -0.064008 -3.993896 0)
			(unlocked yes)
			(layer "B.Fab")
			(hide yes)
			(effects
				(font
					(size 1.016 1.016)
					(thickness 0.1524)
				)
				(justify mirror)
			)
		)
		(property "Device Type" "R402H16"
			(at -0.064008 -5.517896 0)
			(unlocked yes)
			(layer "B.Fab")
			(hide yes)
			(effects
				(font
					(size 1.016 1.016)
					(thickness 0.1524)
				)
				(justify mirror)
			)
		)
		(duplicate_pad_numbers_are_jumpers no)
		(fp_line
			(start -0.508 -0.9398)
			(end 0.508 -0.9398)
			(stroke
				(width 0.1524)
				(type default)
			)
			(layer "B.SilkS")
		)
		(fp_line
			(start 0.508 -0.9398)
			(end 0.508 0.9398)
			(stroke
				(width 0.1524)
				(type default)
			)
			(layer "B.SilkS")
		)
		(fp_rect
			(start 0.508 0.9398)
			(end -0.508 -0.9398)
			(stroke
				(width 0)
				(type default)
			)
			(fill no)
			(layer "B.CrtYd")
		)
		(fp_rect
			(start 0.508 0.9398)
			(end -0.508 -0.9398)
			(stroke
				(width 0)
				(type default)
			)
			(fill no)
			(layer "B.Fab")
		)
		(pad "1" smd custom
			(at 0 -0.4445 180)
			(size 0.1397 0.1397)
			(layers "B.Cu" "B.Mask" "B.Paste")
			(net "P1V2_STBY")
			(options
				(clearance outline)
				(anchor circle)
			)
			(primitives
				(gr_poly
					(pts
						(arc
							(start -0.1778 0.2794)
							(mid -0.249642 0.249642)
							(end -0.2794 0.1778)
						)
						(arc
							(start -0.2794 -0.1778)
							(mid -0.249642 -0.249642)
							(end -0.1778 -0.2794)
						)
						(arc
							(start 0.1778 -0.2794)
							(mid 0.249642 -0.249642)
							(end 0.2794 -0.1778)
						)
						(arc
							(start 0.2794 0.1778)
							(mid 0.249642 0.249642)
							(end 0.1778 0.2794)
						)
					)
					(width 0)
					(fill yes)
				)
			)
		)
		(pad "2" smd custom
			(at 0 0.4445 180)
			(size 0.1397 0.1397)
			(layers "B.Cu" "B.Mask" "B.Paste")
			(net "ADC_P1V2_STBY")
			(options
				(clearance outline)
				(anchor circle)
			)
			(primitives
				(gr_poly
					(pts
						(arc
							(start -0.1778 0.2794)
							(mid -0.249642 0.249642)
							(end -0.2794 0.1778)
						)
						(arc
							(start -0.2794 -0.1778)
							(mid -0.249642 -0.249642)
							(end -0.1778 -0.2794)
						)
						(arc
							(start 0.1778 -0.2794)
							(mid 0.249642 -0.249642)
							(end 0.2794 -0.1778)
						)
						(arc
							(start 0.2794 0.1778)
							(mid 0.249642 0.249642)
							(end 0.1778 0.2794)
						)
					)
					(width 0)
					(fill yes)
				)
			)
		)
	)
	(footprint ""
		(layer "B.Cu")
		(at 111.6838 -9.6012 90)
		(property "Reference" "R461"
			(at 0 0 90)
			(layer "B.SilkS")
			(hide yes)
			(effects
				(font
					(size 1.27 1.27)
				)
				(justify mirror)
			)
		)
		(property "Value" "100KR2J-4-GP"
			(at -0.064008 -3.993896 90)
			(unlocked yes)
			(layer "B.Fab")
			(hide yes)
			(effects
				(font
					(size 1.016 1.016)
					(thickness 0.1524)
				)
				(justify mirror)
			)
		)
		(property "Device Type" "R402H15"
			(at -0.064008 -5.517896 90)
			(unlocked yes)
			(layer "B.Fab")
			(hide yes)
			(effects
				(font
					(size 1.016 1.016)
					(thickness 0.1524)
				)
				(justify mirror)
			)
		)
		(duplicate_pad_numbers_are_jumpers no)
		(fp_line
			(start 0.508 -0.9398)
			(end 0.508 0.9398)
			(stroke
				(width 0.1524)
				(type default)
			)
			(layer "B.SilkS")
		)
		(fp_line
			(start -0.508 -0.9398)
			(end 0.508 -0.9398)
			(stroke
				(width 0.1524)
				(type default)
			)
			(layer "B.SilkS")
		)
		(fp_rect
			(start 0.508 0.9398)
			(end -0.508 -0.9398)
			(stroke
				(width 0)
				(type default)
			)
			(fill no)
			(layer "B.CrtYd")
		)
		(fp_rect
			(start 0.508 0.9398)
			(end -0.508 -0.9398)
			(stroke
				(width 0)
				(type default)
			)
			(fill no)
			(layer "B.Fab")
		)
		(pad "1" smd custom
			(at 0 -0.4445 270)
			(size 0.1397 0.1397)
			(layers "B.Cu" "B.Mask" "B.Paste")
			(net "MB0_VCAP_R")
			(options
				(clearance outline)
				(anchor circle)
			)
			(primitives
				(gr_poly
					(pts
						(arc
							(start -0.1778 0.2794)
							(mid -0.249642 0.249642)
							(end -0.2794 0.1778)
						)
						(arc
							(start -0.2794 -0.1778)
							(mid -0.249642 -0.249642)
							(end -0.1778 -0.2794)
						)
						(arc
							(start 0.1778 -0.2794)
							(mid 0.249642 -0.249642)
							(end 0.2794 -0.1778)
						)
						(arc
							(start 0.2794 0.1778)
							(mid 0.249642 0.249642)
							(end 0.1778 0.2794)
						)
					)
					(width 0)
					(fill yes)
				)
			)
		)
		(pad "2" smd custom
			(at 0 0.4445 270)
			(size 0.1397 0.1397)
			(layers "B.Cu" "B.Mask" "B.Paste")
			(net "MB0_ISTART_R")
			(options
				(clearance outline)
				(anchor circle)
			)
			(primitives
				(gr_poly
					(pts
						(arc
							(start -0.1778 0.2794)
							(mid -0.249642 0.249642)
							(end -0.2794 0.1778)
						)
						(arc
							(start -0.2794 -0.1778)
							(mid -0.249642 -0.249642)
							(end -0.1778 -0.2794)
						)
						(arc
							(start 0.1778 -0.2794)
							(mid 0.249642 -0.249642)
							(end 0.2794 -0.1778)
						)
						(arc
							(start 0.2794 0.1778)
							(mid 0.249642 0.249642)
							(end 0.1778 0.2794)
						)
					)
					(width 0)
					(fill yes)
				)
			)
		)
	)
	(footprint ""
		(layer "B.Cu")
		(at 207.014064 -88.090756 180)
		(property "Reference" "R802"
			(at 0 0 0)
			(layer "B.SilkS")
			(hide yes)
			(effects
				(font
					(size 1.27 1.27)
				)
				(justify mirror)
			)
		)
		(property "Value" "4K7R2F-GP"
			(at -0.064008 -3.993896 180)
			(unlocked yes)
			(layer "B.Fab")
			(hide yes)
			(effects
				(font
					(size 1.016 1.016)
					(thickness 0.1524)
				)
				(justify mirror)
			)
		)
		(property "Device Type" "R402H16"
			(at -0.064008 -5.517896 180)
			(unlocked yes)
			(layer "B.Fab")
			(hide yes)
			(effects
				(font
					(size 1.016 1.016)
					(thickness 0.1524)
				)
				(justify mirror)
			)
		)
		(duplicate_pad_numbers_are_jumpers no)
		(fp_line
			(start 0.508 -0.9398)
			(end 0.508 0.9398)
			(stroke
				(width 0.1524)
				(type default)
			)
			(layer "B.SilkS")
		)
		(fp_line
			(start -0.508 -0.9398)
			(end 0.508 -0.9398)
			(stroke
				(width 0.1524)
				(type default)
			)
			(layer "B.SilkS")
		)
		(fp_rect
			(start 0.508 0.9398)
			(end -0.508 -0.9398)
			(stroke
				(width 0)
				(type default)
			)
			(fill no)
			(layer "B.CrtYd")
		)
		(fp_rect
			(start 0.508 0.9398)
			(end -0.508 -0.9398)
			(stroke
				(width 0)
				(type default)
			)
			(fill no)
			(layer "B.Fab")
		)
		(pad "1" smd custom
			(at 0 -0.4445)
			(size 0.1397 0.1397)
			(layers "B.Cu" "B.Mask" "B.Paste")
			(net "Q21_G")
			(options
				(clearance outline)
				(anchor circle)
			)
			(primitives
				(gr_poly
					(pts
						(arc
							(start -0.1778 0.2794)
							(mid -0.249642 0.249642)
							(end -0.2794 0.1778)
						)
						(arc
							(start -0.2794 -0.1778)
							(mid -0.249642 -0.249642)
							(end -0.1778 -0.2794)
						)
						(arc
							(start 0.1778 -0.2794)
							(mid 0.249642 -0.249642)
							(end 0.2794 -0.1778)
						)
						(arc
							(start 0.2794 0.1778)
							(mid 0.249642 0.249642)
							(end 0.1778 0.2794)
						)
					)
					(width 0)
					(fill yes)
				)
			)
		)
		(pad "2" smd custom
			(at 0 0.4445)
			(size 0.1397 0.1397)
			(layers "B.Cu" "B.Mask" "B.Paste")
			(net "P3V3_STBY")
			(options
				(clearance outline)
				(anchor circle)
			)
			(primitives
				(gr_poly
					(pts
						(arc
							(start -0.1778 0.2794)
							(mid -0.249642 0.249642)
							(end -0.2794 0.1778)
						)
						(arc
							(start -0.2794 -0.1778)
							(mid -0.249642 -0.249642)
							(end -0.1778 -0.2794)
						)
						(arc
							(start 0.1778 -0.2794)
							(mid 0.249642 -0.249642)
							(end 0.2794 -0.1778)
						)
						(arc
							(start 0.2794 0.1778)
							(mid 0.249642 0.249642)
							(end 0.1778 0.2794)
						)
					)
					(width 0)
					(fill yes)
				)
			)
		)
	)
	(footprint ""
		(layer "B.Cu")
		(at 56.9722 -140.335)
		(property "Reference" "TP76"
			(at 0 0 0)
			(layer "B.SilkS")
			(hide yes)
			(effects
				(font
					(size 1.27 1.27)
				)
				(justify mirror)
			)
		)
		(property "Value" "TPAD28-2-GP"
			(at 0.0127 -1.6637 0)
			(unlocked yes)
			(layer "B.Fab")
			(hide yes)
			(effects
				(font
					(size 1.016 1.016)
					(thickness 0.1524)
				)
				(justify mirror)
			)
		)
		(property "Device Type" "TPAD28"
			(at 0.0127 -3.1877 0)
			(unlocked yes)
			(layer "B.Fab")
			(hide yes)
			(effects
				(font
					(size 1.016 1.016)
					(thickness 0.1524)
				)
				(justify mirror)
			)
		)
		(duplicate_pad_numbers_are_jumpers no)
		(fp_poly
			(pts
				(arc
					(start 0.3556 0)
					(mid -0.3556 0)
					(end 0.3556 0)
				)
			)
			(stroke
				(width 0)
				(type default)
			)
			(fill no)
			(layer "B.CrtYd")
		)
		(fp_poly
			(pts
				(arc
					(start 0.6096 0)
					(mid -0.6096 0)
					(end 0.6096 0)
				)
			)
			(stroke
				(width 0)
				(type default)
			)
			(fill no)
			(layer "B.Fab")
		)
		(pad "1" smd circle
			(at 0 0 180)
			(size 0.7112 0.7112)
			(layers "B.Cu" "B.Mask" "B.Paste")
			(net "TP_BMC_GPIOI3")
		)
	)
	(footprint ""
		(layer "B.Cu")
		(at 54.102 -132.08 180)
		(property "Reference" "C115"
			(at 0 0 0)
			(layer "B.SilkS")
			(hide yes)
			(effects
				(font
					(size 1.27 1.27)
				)
				(justify mirror)
			)
		)
		(property "Value" "SC10U6D3V3KX-1-GP"
			(at 0 -2.8194 180)
			(unlocked yes)
			(layer "B.Fab")
			(hide yes)
			(effects
				(font
					(size 1.016 1.016)
					(thickness 0.1524)
				)
				(justify mirror)
			)
		)
		(property "Device Type" "C603H40"
			(at 0 -4.3434 180)
			(unlocked yes)
			(layer "B.Fab")
			(hide yes)
			(effects
				(font
					(size 1.016 1.016)
					(thickness 0.1524)
				)
				(justify mirror)
			)
		)
		(duplicate_pad_numbers_are_jumpers no)
		(fp_line
			(start -0.508 0)
			(end 0.508 0)
			(stroke
				(width 0.2032)
				(type default)
			)
			(layer "B.SilkS")
		)
		(fp_rect
			(start 0.5842 1.3335)
			(end -0.5842 -1.3335)
			(stroke
				(width 0)
				(type default)
			)
			(fill no)
			(layer "B.CrtYd")
		)
		(fp_rect
			(start 0.5842 1.3335)
			(end -0.5842 -1.3335)
			(stroke
				(width 0)
				(type default)
			)
			(fill no)
			(layer "B.Fab")
		)
		(pad "1" smd custom
			(at 0 -0.762)
			(size 0.2159 0.2159)
			(layers "B.Cu" "B.Mask" "B.Paste")
			(net "GND")
			(options
				(clearance outline)
				(anchor circle)
			)
			(primitives
				(gr_poly
					(pts
						(arc
							(start -0.3302 0.4318)
							(mid -0.402042 0.402042)
							(end -0.4318 0.3302)
						)
						(arc
							(start -0.4318 -0.3302)
							(mid -0.402042 -0.402042)
							(end -0.3302 -0.4318)
						)
						(arc
							(start 0.3302 -0.4318)
							(mid 0.402042 -0.402042)
							(end 0.4318 -0.3302)
						)
						(arc
							(start 0.4318 0.3302)
							(mid 0.402042 0.402042)
							(end 0.3302 0.4318)
						)
					)
					(width 0)
					(fill yes)
				)
			)
		)
		(pad "2" smd custom
			(at 0 0.762)
			(size 0.2159 0.2159)
			(layers "B.Cu" "B.Mask" "B.Paste")
			(net "P1V15_STBY")
			(options
				(clearance outline)
				(anchor circle)
			)
			(primitives
				(gr_poly
					(pts
						(arc
							(start -0.3302 0.4318)
							(mid -0.402042 0.402042)
							(end -0.4318 0.3302)
						)
						(arc
							(start -0.4318 -0.3302)
							(mid -0.402042 -0.402042)
							(end -0.3302 -0.4318)
						)
						(arc
							(start 0.3302 -0.4318)
							(mid 0.402042 -0.402042)
							(end 0.4318 -0.3302)
						)
						(arc
							(start 0.4318 0.3302)
							(mid 0.402042 0.402042)
							(end 0.3302 0.4318)
						)
					)
					(width 0)
					(fill yes)
				)
			)
		)
	)
	(footprint ""
		(layer "B.Cu")
		(at 36.585398 -140.280644)
		(property "Reference" "C104"
			(at 0 0 0)
			(layer "B.SilkS")
			(hide yes)
			(effects
				(font
					(size 1.27 1.27)
				)
				(justify mirror)
			)
		)
		(property "Value" "SC10U6D3V3KX-1-GP"
			(at 0 -2.8194 0)
			(unlocked yes)
			(layer "B.Fab")
			(hide yes)
			(effects
				(font
					(size 1.016 1.016)
					(thickness 0.1524)
				)
				(justify mirror)
			)
		)
		(property "Device Type" "C603H40"
			(at 0 -4.3434 0)
			(unlocked yes)
			(layer "B.Fab")
			(hide yes)
			(effects
				(font
					(size 1.016 1.016)
					(thickness 0.1524)
				)
				(justify mirror)
			)
		)
		(duplicate_pad_numbers_are_jumpers no)
		(fp_line
			(start -0.508 0)
			(end 0.508 0)
			(stroke
				(width 0.2032)
				(type default)
			)
			(layer "B.SilkS")
		)
		(fp_rect
			(start 0.5842 1.3335)
			(end -0.5842 -1.3335)
			(stroke
				(width 0)
				(type default)
			)
			(fill no)
			(layer "B.CrtYd")
		)
		(fp_rect
			(start 0.5842 1.3335)
			(end -0.5842 -1.3335)
			(stroke
				(width 0)
				(type default)
			)
			(fill no)
			(layer "B.Fab")
		)
		(pad "1" smd custom
			(at 0 -0.762 180)
			(size 0.2159 0.2159)
			(layers "B.Cu" "B.Mask" "B.Paste")
			(net "GND")
			(options
				(clearance outline)
				(anchor circle)
			)
			(primitives
				(gr_poly
					(pts
						(arc
							(start -0.3302 0.4318)
							(mid -0.402042 0.402042)
							(end -0.4318 0.3302)
						)
						(arc
							(start -0.4318 -0.3302)
							(mid -0.402042 -0.402042)
							(end -0.3302 -0.4318)
						)
						(arc
							(start 0.3302 -0.4318)
							(mid 0.402042 -0.402042)
							(end 0.4318 -0.3302)
						)
						(arc
							(start 0.4318 0.3302)
							(mid 0.402042 0.402042)
							(end 0.3302 0.4318)
						)
					)
					(width 0)
					(fill yes)
				)
			)
		)
		(pad "2" smd custom
			(at 0 0.762 180)
			(size 0.2159 0.2159)
			(layers "B.Cu" "B.Mask" "B.Paste")
			(net "P3V3_STBY")
			(options
				(clearance outline)
				(anchor circle)
			)
			(primitives
				(gr_poly
					(pts
						(arc
							(start -0.3302 0.4318)
							(mid -0.402042 0.402042)
							(end -0.4318 0.3302)
						)
						(arc
							(start -0.4318 -0.3302)
							(mid -0.402042 -0.402042)
							(end -0.3302 -0.4318)
						)
						(arc
							(start 0.3302 -0.4318)
							(mid 0.402042 -0.402042)
							(end 0.4318 -0.3302)
						)
						(arc
							(start 0.4318 0.3302)
							(mid 0.402042 0.402042)
							(end 0.3302 0.4318)
						)
					)
					(width 0)
					(fill yes)
				)
			)
		)
	)
	(footprint ""
		(layer "B.Cu")
		(at 55.788052 -146.395186)
		(property "Reference" "TP81"
			(at 0 0 0)
			(layer "B.SilkS")
			(hide yes)
			(effects
				(font
					(size 1.27 1.27)
				)
				(justify mirror)
			)
		)
		(property "Value" "TPAD28-2-GP"
			(at 0.0127 -1.6637 0)
			(unlocked yes)
			(layer "B.Fab")
			(hide yes)
			(effects
				(font
					(size 1.016 1.016)
					(thickness 0.1524)
				)
				(justify mirror)
			)
		)
		(property "Device Type" "TPAD28"
			(at 0.0127 -3.1877 0)
			(unlocked yes)
			(layer "B.Fab")
			(hide yes)
			(effects
				(font
					(size 1.016 1.016)
					(thickness 0.1524)
				)
				(justify mirror)
			)
		)
		(duplicate_pad_numbers_are_jumpers no)
		(fp_poly
			(pts
				(arc
					(start 0.3556 0)
					(mid -0.3556 0)
					(end 0.3556 0)
				)
			)
			(stroke
				(width 0)
				(type default)
			)
			(fill no)
			(layer "B.CrtYd")
		)
		(fp_poly
			(pts
				(arc
					(start 0.6096 0)
					(mid -0.6096 0)
					(end 0.6096 0)
				)
			)
			(stroke
				(width 0)
				(type default)
			)
			(fill no)
			(layer "B.Fab")
		)
		(pad "1" smd circle
			(at 0 0 180)
			(size 0.7112 0.7112)
			(layers "B.Cu" "B.Mask" "B.Paste")
			(net "JTAG_BMC_TCK")
		)
	)
	(footprint ""
		(layer "B.Cu")
		(at 37.80536 -140.29309 180)
		(property "Reference" "C99"
			(at 0 0 0)
			(layer "B.SilkS")
			(hide yes)
			(effects
				(font
					(size 1.27 1.27)
				)
				(justify mirror)
			)
		)
		(property "Value" "SC1U16V3KX-5GP"
			(at 0 -2.8194 180)
			(unlocked yes)
			(layer "B.Fab")
			(hide yes)
			(effects
				(font
					(size 1.016 1.016)
					(thickness 0.1524)
				)
				(justify mirror)
			)
		)
		(property "Device Type" "C603H36"
			(at 0 -4.3434 180)
			(unlocked yes)
			(layer "B.Fab")
			(hide yes)
			(effects
				(font
					(size 1.016 1.016)
					(thickness 0.1524)
				)
				(justify mirror)
			)
		)
		(duplicate_pad_numbers_are_jumpers no)
		(fp_line
			(start -0.508 0)
			(end 0.508 0)
			(stroke
				(width 0.2032)
				(type default)
			)
			(layer "B.SilkS")
		)
		(fp_rect
			(start 0.5842 1.3335)
			(end -0.5842 -1.3335)
			(stroke
				(width 0)
				(type default)
			)
			(fill no)
			(layer "B.CrtYd")
		)
		(fp_rect
			(start 0.5842 1.3335)
			(end -0.5842 -1.3335)
			(stroke
				(width 0)
				(type default)
			)
			(fill no)
			(layer "B.Fab")
		)
		(pad "1" smd custom
			(at 0 -0.762)
			(size 0.2159 0.2159)
			(layers "B.Cu" "B.Mask" "B.Paste")
			(net "P3V3_STBY")
			(options
				(clearance outline)
				(anchor circle)
			)
			(primitives
				(gr_poly
					(pts
						(arc
							(start -0.3302 0.4318)
							(mid -0.402042 0.402042)
							(end -0.4318 0.3302)
						)
						(arc
							(start -0.4318 -0.3302)
							(mid -0.402042 -0.402042)
							(end -0.3302 -0.4318)
						)
						(arc
							(start 0.3302 -0.4318)
							(mid 0.402042 -0.402042)
							(end 0.4318 -0.3302)
						)
						(arc
							(start 0.4318 0.3302)
							(mid 0.402042 0.402042)
							(end 0.3302 0.4318)
						)
					)
					(width 0)
					(fill yes)
				)
			)
		)
		(pad "2" smd custom
			(at 0 0.762)
			(size 0.2159 0.2159)
			(layers "B.Cu" "B.Mask" "B.Paste")
			(net "GND")
			(options
				(clearance outline)
				(anchor circle)
			)
			(primitives
				(gr_poly
					(pts
						(arc
							(start -0.3302 0.4318)
							(mid -0.402042 0.402042)
							(end -0.4318 0.3302)
						)
						(arc
							(start -0.4318 -0.3302)
							(mid -0.402042 -0.402042)
							(end -0.3302 -0.4318)
						)
						(arc
							(start 0.3302 -0.4318)
							(mid 0.402042 -0.402042)
							(end 0.4318 -0.3302)
						)
						(arc
							(start 0.4318 0.3302)
							(mid 0.402042 0.402042)
							(end 0.3302 0.4318)
						)
					)
					(width 0)
					(fill yes)
				)
			)
		)
	)
)
